# S9S_MB_2U (Grand Teton) — schematic netlist excerpt (pin names and nets, part order shuffled) for the footprints in the layout excerpt that follows; sources: Cadence DE-HDL packaged netlist, KiCad conversion of 03242023_DA0F0TMBIJ0_F0T_Motherboard_J_brd_V01_OCP.brd

PR634  Q_RES  10K 1% EMPTY  pkg 0402LF  page 278 : A = PVCCD_HV_CPU0_ATSEN ; B = GND
PR2336  Q_RES  26.1K 0.1% EMPTY  pkg 0402LF  page 281 : A = PVPP_HBM_CPU0_FB ; B = FM_HBM_VPP_SEL_CPU0_D

(kicad_pcb
	(version 20260206)
	(generator "pcbnew")
	(generator_version "10.0")
	(general
		(thickness 1.6)
		(legacy_teardrops no)
	)
	(paper "A4")
	(title_block
		(title "03242023_DA0F0TMBIJ0_F0T_Motherboard_J_brd_V01_OCP.brd")
		(comment 1 "Grand Teton / footprints 3575-3576 of 6105")
	)
	(layers
		(0 "F.Cu" signal "TOP")
		(4 "In1.Cu" signal "GND")
		(6 "In2.Cu" signal "IN1")
		(8 "In3.Cu" signal "GND1")
		(10 "In4.Cu" signal "IN2")
		(12 "In5.Cu" signal "GND2")
		(14 "In6.Cu" signal "IN3")
		(16 "In7.Cu" signal "GND3")
		(18 "In8.Cu" signal "VCC")
		(20 "In9.Cu" signal "VCC1")
		(22 "In10.Cu" signal "GND4")
		(24 "In11.Cu" signal "IN4")
		(26 "In12.Cu" signal "GND5")
		(28 "In13.Cu" signal "IN5")
		(30 "In14.Cu" signal "GND6")
		(32 "In15.Cu" signal "IN6")
		(34 "In16.Cu" signal "GND7")
		(2 "B.Cu" signal "BOTTOM")
		(9 "F.Adhes" user "F.Adhesive")
		(11 "B.Adhes" user "B.Adhesive")
		(13 "F.Paste" user "Package Geometry/Pastemask Top")
		(15 "B.Paste" user "Package Geometry/Pastemask Bottom")
		(5 "F.SilkS" user "Ref Des/Silkscreen Top")
		(7 "B.SilkS" user "Ref Des/Silkscreen Bottom")
		(1 "F.Mask" user "Board Geometry/Soldermask Top")
		(3 "B.Mask" user "Board Geometry/Soldermask Bottom")
		(17 "Dwgs.User" user "User.Drawings")
		(19 "Cmts.User" user "User.Comments")
		(21 "Eco1.User" user "User.Eco1")
		(23 "Eco2.User" user "User.Eco2")
		(25 "Edge.Cuts" user "Board Geometry/Outline")
		(27 "Margin" user)
		(31 "F.CrtYd" user "Package Geometry/Place Bound Top")
		(29 "B.CrtYd" user "Package Geometry/Place Bound Bottom")
		(35 "F.Fab" user "Ref Des/Assembly Top")
		(33 "B.Fab" user "Ref Des/Assembly Bottom")
	)
	(footprint ""
		(layer "F.Cu")
		(at 427.097952 -124.91466 180)
		(property "Reference" "PR634"
			(at 0 0 180)
			(layer "F.SilkS")
			(hide yes)
			(effects
				(font
					(size 1.27 1.27)
				)
			)
		)
		(property "Value" ""
			(at 0 0 180)
			(layer "F.Fab")
			(effects
				(font
					(size 1.27 1.27)
				)
			)
		)
		(duplicate_pad_numbers_are_jumpers no)
		(fp_line
			(start 0.7874 0.4064)
			(end -0.7874 0.4064)
			(stroke
				(width 0.1524)
				(type default)
			)
			(layer "F.SilkS")
		)
		(fp_line
			(start 0.7874 -0.4064)
			(end 0.7874 0.4064)
			(stroke
				(width 0.1524)
				(type default)
			)
			(layer "F.SilkS")
		)
		(fp_line
			(start -0.7874 0.4064)
			(end -0.7874 -0.4064)
			(stroke
				(width 0.1524)
				(type default)
			)
			(layer "F.SilkS")
		)
		(fp_line
			(start -0.7874 -0.4064)
			(end 0.7874 -0.4064)
			(stroke
				(width 0.1524)
				(type default)
			)
			(layer "F.SilkS")
		)
		(fp_line
			(start 0.67945 0.3048)
			(end 0.120396 0.3048)
			(stroke
				(width 0.1)
				(type default)
			)
			(layer "F.Fab")
		)
		(fp_line
			(start 0.67945 -0.3048)
			(end 0.67945 0.3048)
			(stroke
				(width 0.1)
				(type default)
			)
			(layer "F.Fab")
		)
		(fp_line
			(start 0.12065 -0.2794)
			(end 0.12065 -0.3048)
			(stroke
				(width 0.1)
				(type default)
			)
			(layer "F.Fab")
		)
		(fp_line
			(start 0.12065 -0.3048)
			(end 0.67945 -0.3048)
			(stroke
				(width 0.1)
				(type default)
			)
			(layer "F.Fab")
		)
		(fp_line
			(start 0.120396 0.3048)
			(end 0.120396 0.2794)
			(stroke
				(width 0.1)
				(type default)
			)
			(layer "F.Fab")
		)
		(fp_line
			(start 0.120396 0.2794)
			(end -0.12065 0.2794)
			(stroke
				(width 0.1)
				(type default)
			)
			(layer "F.Fab")
		)
		(fp_line
			(start -0.12065 0.3048)
			(end -0.67945 0.3048)
			(stroke
				(width 0.1)
				(type default)
			)
			(layer "F.Fab")
		)
		(fp_line
			(start -0.12065 0.2794)
			(end -0.12065 0.3048)
			(stroke
				(width 0.1)
				(type default)
			)
			(layer "F.Fab")
		)
		(fp_line
			(start -0.12065 -0.2794)
			(end 0.12065 -0.2794)
			(stroke
				(width 0.1)
				(type default)
			)
			(layer "F.Fab")
		)
		(fp_line
			(start -0.12065 -0.305054)
			(end -0.12065 -0.2794)
			(stroke
				(width 0.1)
				(type default)
			)
			(layer "F.Fab")
		)
		(fp_line
			(start -0.67945 0.3048)
			(end -0.67945 -0.305054)
			(stroke
				(width 0.1)
				(type default)
			)
			(layer "F.Fab")
		)
		(fp_line
			(start -0.67945 -0.305054)
			(end -0.12065 -0.305054)
			(stroke
				(width 0.1)
				(type default)
			)
			(layer "F.Fab")
		)
		(pad "1" smd circle
			(at -0.40005 0 180)
			(size 0 0)
			(layers "F.Cu" "F.Mask" "F.Paste")
			(net "PVCCD_HV_CPU0_ATSEN")
		)
		(pad "2" smd circle
			(at 0.40005 0 180)
			(size 0 0)
			(layers "F.Cu" "F.Mask" "F.Paste")
			(net "GND")
		)
	)
	(footprint ""
		(layer "F.Cu")
		(at 366.95888 -357.114348 90)
		(property "Reference" "PR2336"
			(at 0 0 90)
			(layer "F.SilkS")
			(hide yes)
			(effects
				(font
					(size 1.27 1.27)
				)
			)
		)
		(property "Value" ""
			(at 0 0 90)
			(layer "F.Fab")
			(effects
				(font
					(size 1.27 1.27)
				)
			)
		)
		(duplicate_pad_numbers_are_jumpers no)
		(fp_line
			(start 0.7874 -0.4064)
			(end 0.7874 0.4064)
			(stroke
				(width 0.1524)
				(type default)
			)
			(layer "F.SilkS")
		)
		(fp_line
			(start -0.7874 -0.4064)
			(end 0.7874 -0.4064)
			(stroke
				(width 0.1524)
				(type default)
			)
			(layer "F.SilkS")
		)
		(fp_line
			(start 0.7874 0.4064)
			(end -0.7874 0.4064)
			(stroke
				(width 0.1524)
				(type default)
			)
			(layer "F.SilkS")
		)
		(fp_line
			(start -0.7874 0.4064)
			(end -0.7874 -0.4064)
			(stroke
				(width 0.1524)
				(type default)
			)
			(layer "F.SilkS")
		)
		(fp_line
			(start -0.12065 -0.305054)
			(end -0.12065 -0.2794)
			(stroke
				(width 0.1)
				(type default)
			)
			(layer "F.Fab")
		)
		(fp_line
			(start -0.67945 -0.305054)
			(end -0.12065 -0.305054)
			(stroke
				(width 0.1)
				(type default)
			)
			(layer "F.Fab")
		)
		(fp_line
			(start 0.67945 -0.3048)
			(end 0.67945 0.3048)
			(stroke
				(width 0.1)
				(type default)
			)
			(layer "F.Fab")
		)
		(fp_line
			(start 0.12065 -0.3048)
			(end 0.67945 -0.3048)
			(stroke
				(width 0.1)
				(type default)
			)
			(layer "F.Fab")
		)
		(fp_line
			(start 0.12065 -0.2794)
			(end 0.12065 -0.3048)
			(stroke
				(width 0.1)
				(type default)
			)
			(layer "F.Fab")
		)
		(fp_line
			(start -0.12065 -0.2794)
			(end 0.12065 -0.2794)
			(stroke
				(width 0.1)
				(type default)
			)
			(layer "F.Fab")
		)
		(fp_line
			(start 0.120396 0.2794)
			(end -0.12065 0.2794)
			(stroke
				(width 0.1)
				(type default)
			)
			(layer "F.Fab")
		)
		(fp_line
			(start -0.12065 0.2794)
			(end -0.12065 0.3048)
			(stroke
				(width 0.1)
				(type default)
			)
			(layer "F.Fab")
		)
		(fp_line
			(start 0.67945 0.3048)
			(end 0.120396 0.3048)
			(stroke
				(width 0.1)
				(type default)
			)
			(layer "F.Fab")
		)
		(fp_line
			(start 0.120396 0.3048)
			(end 0.120396 0.2794)
			(stroke
				(width 0.1)
				(type default)
			)
			(layer "F.Fab")
		)
		(fp_line
			(start -0.12065 0.3048)
			(end -0.67945 0.3048)
			(stroke
				(width 0.1)
				(type default)
			)
			(layer "F.Fab")
		)
		(fp_line
			(start -0.67945 0.3048)
			(end -0.67945 -0.305054)
			(stroke
				(width 0.1)
				(type default)
			)
			(layer "F.Fab")
		)
		(pad "1" smd circle
			(at -0.40005 0 90)
			(size 0 0)
			(layers "F.Cu" "F.Mask" "F.Paste")
			(net "PVPP_HBM_CPU0_FB")
		)
		(pad "2" smd circle
			(at 0.40005 0 90)
			(size 0 0)
			(layers "F.Cu" "F.Mask" "F.Paste")
			(net "FM_HBM_VPP_SEL_CPU0_D")
		)
	)
)
